G04 ================== begin FILE IDENTIFICATION RECORD ==================*
G04 Layout Name:  D:/<user>/Wistron_project/16318-2/gbr/16318-2.brd*
G04 Film Name:    P_OUTLINE*
G04 File Format:  Gerber RS274X*
G04 File Origin:  Cadence Allegro 16.5-S056*
G04 Origin Date:  Mon Aug 07 11:09:06 2017*
G04 *
G04 Layer:  BOARD GEOMETRY/PANEL_OUTLINE*
G04 *
G04 Offset:    (0.00 0.00)*
G04 Mirror:    No*
G04 Mode:      Positive*
G04 Rotation:  0*
G04 FullContactRelief:  No*
G04 UndefLineWidth:     6.00*
G04 ================== end FILE IDENTIFICATION RECORD ====================*
%FSLAX35Y35*MOIN*%
%IR0*IPPOS*OFA0.00000B0.00000*MIA0B0*SFA1.00000B1.00000*%
%ADD10C,.006*%
G75*
%LPD*%
G75*
G54D10*
G01X3937Y0D02*
X116260D01*
G01X0Y3937D02*
G03X3937Y0I3937J0D01*
G01X0Y723480D02*
Y3937D01*
G01X416Y725241D02*
G03X0Y723480I3521J-1761D01*
G01X18597Y761603D02*
X416Y725241D01*
G01X77756Y98425D02*
G03X63976I-6890J0D01*
G01D02*
G03X77756I6890J0D01*
G01X83071Y245079D02*
G03Y231693I0J-6693D01*
G01X77756Y472441D02*
G03X63976I-6890J0D01*
G01D02*
G03X77756I6890J0D01*
G01X57087Y740157D02*
G03X41339I-7874J0D01*
G01D02*
G03X57087I7874J0D01*
G01X22118Y763780D02*
G03X18597Y761603I1J-3937D01*
G01X386149Y763780D02*
X22118D01*
G01X128071Y3937D02*
G03X132008Y0I3937J0D01*
G01X116260D02*
G03X120197Y3937I0J3937D01*
G01X132008Y0D02*
X275709D01*
G01X120197Y3937D02*
Y429331D01*
G01X128071Y59055D02*
Y3937D01*
G01Y59055D02*
G03X120197I-3937J0D01*
G01X128071D02*
G03X120197I-3937J0D01*
G01X128071Y98425D02*
Y421457D01*
G01X120197Y98425D02*
G03X128071I3937J0D01*
G01X120197D02*
G03X128071I3937J0D01*
G01X96457Y231693D02*
G03Y245079I0J6693D01*
G01X83071D02*
X96457D01*
G01Y231693D02*
X83071D01*
G01X96654Y413583D02*
G03X83661I-6496J0D01*
G01D02*
G03X96654I6496J0D01*
G01X132008Y425394D02*
G03X128071Y421457I0J-3937D01*
G01X124134Y433268D02*
X283583D01*
G01X124134D02*
G03X120197Y429331I0J-3937D01*
G01X184173Y425394D02*
X132008D01*
G01X213480Y37075D02*
G03I-4291J0D01*
G01Y383483D02*
G03I-4291J0D01*
G01X184173Y425394D02*
G03Y433268I0J3937D01*
G01Y425394D02*
G03Y433268I0J3937D01*
G01X171457Y669291D02*
G03X154921I-8268J0D01*
G01D02*
G03X171457I8268J0D01*
G01X223543Y425394D02*
X275709D01*
G01X223543Y433268D02*
G03Y425394I0J-3937D01*
G01Y433268D02*
G03Y425394I0J-3937D01*
G01X275709Y0D02*
G03X279646Y3937I0J3937D01*
G01X291457Y0D02*
X921260D01*
G01X287520Y3937D02*
G03X291457Y0I3937J0D01*
G01X287520Y429331D02*
Y3937D01*
G01X279646Y59055D02*
Y3937D01*
G01X287520Y59055D02*
G03X279646I-3937J0D01*
G01X287520D02*
G03X279646I-3937J0D01*
G01Y98425D02*
Y421457D01*
G01Y98425D02*
G03X287520I3937J0D01*
G01X279646D02*
G03X287520I3937J0D01*
G01X315551Y157677D02*
G03X302559I-6496J0D01*
G01D02*
G03X315551I6496J0D01*
G01X315945Y406890D02*
G03Y420276I0J6693D01*
G01X302559D02*
X315945D01*
G01X302559D02*
G03Y406890I0J-6693D01*
G01X315945D02*
X302559D01*
G01X279646Y421457D02*
G03X275709Y425394I-3937J0D01*
G01X287520Y429331D02*
G03X283583Y433268I-3937J0D01*
G01X321850Y472441D02*
G03X308071I-6889J0D01*
G01D02*
G03X321850I6889J0D01*
G01X412402Y39370D02*
G03X398622I-6890J0D01*
G01D02*
G03X412402I6890J0D01*
G01X371063Y740157D02*
G03X357283I-6890J0D01*
G01D02*
G03X371063I6890J0D01*
G01X403756Y763780D02*
G03X400235Y758082I0J-3937D01*
G01X389671Y761603D02*
G03X386149Y763780I-3522J-1760D01*
G01X414895Y728762D02*
X400235Y758082D01*
G01X407852Y725241D02*
X389671Y761603D01*
G01X403756Y763780D02*
X428096D01*
G01X416142Y200787D02*
G03X420079Y196850I3937J0D01*
G01X408268Y188976D02*
Y723480D01*
G01Y188976D02*
G03X412205I1968J0D01*
G01X556299Y196850D02*
X420079D01*
G01X564173Y188976D02*
X412205D01*
G01X416142Y316929D02*
Y200787D01*
G01Y316929D02*
G03X408268I-3937J0D01*
G01X416142D02*
G03X408268I-3937J0D01*
G01X416142Y347638D02*
Y690803D01*
G01X408268Y347638D02*
G03X416142I3937J0D01*
G01X408268D02*
G03X416142I3937J0D01*
G01Y721512D02*
Y723481D01*
G01Y723482D02*
G03X414894Y728764I-11811J-2D01*
G01X408268Y723480D02*
G03X407852Y725241I-3937J0D01*
G01X408268Y721512D02*
G03X416142I3937J0D01*
G01Y690803D02*
G03X408268I-3937J0D01*
G01Y721512D02*
G03X416142I3937J0D01*
G01Y690803D02*
G03X408268I-3937J0D01*
G01X428096Y763780D02*
G03X435970I3937J0D01*
G01D02*
X572622D01*
G01X483800Y137224D02*
G03X493878I5039J0D01*
G01X493563Y164744D02*
G03X484115I-4724J0D01*
G01D02*
G03X493563I4724J0D01*
G01X493878Y137224D02*
G03X483800I-5039J0D01*
G01X493622Y245605D02*
G03I-4291J0D01*
G01Y698924D02*
G03I-4291J0D01*
G01X556299Y196850D02*
G03X560236Y200787I0J3937D01*
G01X564173Y188976D02*
G03X568110I1968J0D01*
G01Y723480D02*
Y188976D01*
G01X560236Y316929D02*
Y200787D01*
G01X568110Y316929D02*
G03X560236I-3937J0D01*
G01X568110D02*
G03X560236I-3937J0D01*
G01Y690803D02*
Y347638D01*
G01D02*
G03X568110I3937J0D01*
G01X560236D02*
G03X568110I3937J0D01*
G01X560236Y721512D02*
Y723481D01*
G01X561484Y728764D02*
G03X560236Y723482I10563J-5284D01*
G01X568526Y725241D02*
G03X568110Y723480I3521J-1761D01*
G01X560236Y721512D02*
G03X568110I3937J0D01*
G01Y690803D02*
G03X560236I-3937J0D01*
G01Y721512D02*
G03X568110I3937J0D01*
G01Y690803D02*
G03X560236I-3937J0D01*
G01X576143Y758082D02*
G03X572622Y763780I-3521J1761D01*
G01X576143Y758082D02*
X561483Y728762D01*
G01X586707Y761603D02*
X568526Y725241D01*
G01X590228Y763780D02*
G03X586707Y761603I1J-3937D01*
G01X903079Y763780D02*
X590228D01*
G01X634252Y57874D02*
G03X625591I-4331J0D01*
G01D02*
G03X634252I4331J0D01*
G01X658661Y180000D02*
G03X646850I-5905J0D01*
G01D02*
G03X658661I5906J0D01*
G01X619094Y433071D02*
G03X605315I-6889J0D01*
G01D02*
G03X619094I6890J0D01*
G01Y740157D02*
G03X605315I-6889J0D01*
G01D02*
G03X619094I6890J0D01*
G01X712992Y57874D02*
G03X704331I-4331J0D01*
G01D02*
G03X712992I4330J0D01*
G01X859449Y332598D02*
G03X871260I5905J0D01*
G01D02*
G03X859449I-5906J0D01*
G01X921260Y0D02*
G03X925197Y3937I0J3937D01*
G01X883858Y59055D02*
G03X868110I-7874J0D01*
G01D02*
G03X883858I7874J0D01*
G01X925197Y3937D02*
Y723480D01*
G01X882874Y433071D02*
G03X869094I-6890J0D01*
G01D02*
G03X882874I6890J0D01*
G01X925197Y723480D02*
G03X924781Y725241I-3937J0D01*
G01X882874Y740157D02*
G03X869094I-6890J0D01*
G01D02*
G03X882874I6890J0D01*
G01X906600Y761603D02*
G03X903079Y763780I-3522J-1760D01*
G01X924781Y725241D02*
X906600Y761603D01*
M02*
